(kicad_pcb
	(version 20260206)
	(generator "pcbnew")
	(generator_version "10.0")
	(general
		(thickness 1.6)
		(legacy_teardrops no)
	)
	(paper "A4")
	(title_block
		(title "baseboard — 13948-1b.1110WZS1818.brd")
		(comment 1 "Honey Badger (Wiwynn) / footprints 784-785 of 2523")
	)
	(layers
		(0 "F.Cu" signal "TOP")
		(4 "In1.Cu" signal "L2GND")
		(6 "In2.Cu" signal "L3")
		(8 "In3.Cu" signal "L4VCC")
		(10 "In4.Cu" signal "L5VCC")
		(12 "In5.Cu" signal "L6")
		(14 "In6.Cu" signal "L7GND")
		(2 "B.Cu" signal "BOTTOM")
		(9 "F.Adhes" user "F.Adhesive")
		(11 "B.Adhes" user "B.Adhesive")
		(13 "F.Paste" user "Package Geometry/Pastemask Top")
		(15 "B.Paste" user "Package Geometry/Pastemask Bottom")
		(5 "F.SilkS" user "Ref Des/Silkscreen Top")
		(7 "B.SilkS" user "Ref Des/Silkscreen Bottom")
		(1 "F.Mask" user "Board Geometry/Soldermask Top")
		(3 "B.Mask" user "Board Geometry/Soldermask Bottom")
		(17 "Dwgs.User" user "User.Drawings")
		(19 "Cmts.User" user "User.Comments")
		(21 "Eco1.User" user "User.Eco1")
		(23 "Eco2.User" user "User.Eco2")
		(25 "Edge.Cuts" user "Board Geometry/Outline")
		(27 "Margin" user)
		(31 "F.CrtYd" user "Package Geometry/Place Bound Top")
		(29 "B.CrtYd" user "Package Geometry/Place Bound Bottom")
		(35 "F.Fab" user "Ref Des/Assembly Top")
		(33 "B.Fab" user "Ref Des/Assembly Bottom")
	)
	(footprint ""
		(layer "F.Cu")
		(at 20.135088 -188.215016 180)
		(property "Reference" "SU17"
			(at 0 0 180)
			(layer "F.SilkS")
			(hide yes)
			(effects
				(font
					(size 1.27 1.27)
				)
			)
		)
		(property "Value" "PCA9575PW2-GP"
			(at 0.635 -8.0772 180)
			(unlocked yes)
			(layer "F.Fab")
			(hide yes)
			(effects
				(font
					(size 1.016 1.016)
					(thickness 0.1524)
				)
			)
		)
		(property "Device Type" "TSOIC28H44"
			(at 0.635 -9.9822 180)
			(unlocked yes)
			(layer "F.Fab")
			(hide yes)
			(effects
				(font
					(size 1.016 1.016)
					(thickness 0.1524)
				)
			)
		)
		(duplicate_pad_numbers_are_jumpers no)
		(fp_line
			(start 4.4704 1.3716)
			(end -5.3467 1.3716)
			(stroke
				(width 0.1524)
				(type default)
			)
			(layer "F.SilkS")
		)
		(fp_line
			(start 4.4704 -1.3716)
			(end 4.4704 1.3716)
			(stroke
				(width 0.1524)
				(type default)
			)
			(layer "F.SilkS")
		)
		(fp_line
			(start -4.84632 0.00254)
			(end -5.3467 0.50292)
			(stroke
				(width 0.1524)
				(type default)
			)
			(layer "F.SilkS")
		)
		(fp_line
			(start -4.84632 0)
			(end -4.84632 0.00254)
			(stroke
				(width 0.1524)
				(type default)
			)
			(layer "F.SilkS")
		)
		(fp_line
			(start -5.3467 4.572)
			(end -5.3467 -1.3716)
			(stroke
				(width 0.1524)
				(type default)
			)
			(layer "F.SilkS")
		)
		(fp_line
			(start -5.3467 1.7907)
			(end -5.3467 4.572)
			(stroke
				(width 0.508)
				(type default)
			)
			(layer "F.SilkS")
		)
		(fp_line
			(start -5.3467 -0.50038)
			(end -4.84632 0)
			(stroke
				(width 0.1524)
				(type default)
			)
			(layer "F.SilkS")
		)
		(fp_line
			(start -5.3467 -0.50292)
			(end -5.3467 -0.50038)
			(stroke
				(width 0.1524)
				(type default)
			)
			(layer "F.SilkS")
		)
		(fp_line
			(start -5.3467 -1.3716)
			(end 4.4704 -1.3716)
			(stroke
				(width 0.1524)
				(type default)
			)
			(layer "F.SilkS")
		)
		(fp_poly
			(pts
				(xy -4.55549 -1.8288) (xy -4.55549 1.8288) (xy 4.55549 1.8288) (xy 4.55549 -1.8288)
			)
			(stroke
				(width 0)
				(type default)
			)
			(fill yes)
			(layer "F.SilkS")
		)
		(fp_poly
			(pts
				(xy -5.3594 -4.0767) (xy 5.3594 -4.0767) (xy 5.3594 4.0767) (xy -5.3594 4.0767)
			)
			(stroke
				(width 0)
				(type default)
			)
			(fill no)
			(layer "F.CrtYd")
		)
		(fp_poly
			(pts
				(xy -5.3594 -4.0767) (xy 5.3594 -4.0767) (xy 5.3594 4.0767) (xy -5.3594 4.0767)
			)
			(stroke
				(width 0)
				(type default)
			)
			(fill no)
			(layer "F.Fab")
		)
		(pad "1" smd rect
			(at -4.22529 2.80543 180)
			(size 0.3556 1.524)
			(layers "F.Cu" "F.Mask" "F.Paste")
			(net "IO_EXP_HDD_PRE_A0")
		)
		(pad "2" smd rect
			(at -3.57505 2.80543 180)
			(size 0.3556 1.524)
			(layers "F.Cu" "F.Mask" "F.Paste")
			(net "P1V8_E")
		)
		(pad "3" smd rect
			(at -2.92481 2.80543 180)
			(size 0.3556 1.524)
			(layers "F.Cu" "F.Mask" "F.Paste")
			(net "I2C_IO_EXP_RESET#_PRST")
		)
		(pad "4" smd rect
			(at -2.27457 2.80543 180)
			(size 0.3556 1.524)
			(layers "F.Cu" "F.Mask" "F.Paste")
			(net "SAS_HDD_PRE0")
		)
		(pad "5" smd rect
			(at -1.6256 2.80543 180)
			(size 0.3556 1.524)
			(layers "F.Cu" "F.Mask" "F.Paste")
			(net "SAS_HDD_PRE1")
		)
		(pad "6" smd rect
			(at -0.97536 2.80543 180)
			(size 0.3556 1.524)
			(layers "F.Cu" "F.Mask" "F.Paste")
			(net "SAS_HDD_PRE2")
		)
		(pad "7" smd rect
			(at -0.32512 2.80543 180)
			(size 0.3556 1.524)
			(layers "F.Cu" "F.Mask" "F.Paste")
			(net "SAS_HDD_PRE3")
		)
		(pad "8" smd rect
			(at 0.32512 2.80543 180)
			(size 0.3556 1.524)
			(layers "F.Cu" "F.Mask" "F.Paste")
			(net "IO_EXP_HDD_PRE_A1")
		)
		(pad "9" smd rect
			(at 0.97536 2.80543 180)
			(size 0.3556 1.524)
			(layers "F.Cu" "F.Mask" "F.Paste")
			(net "P3V3_STBY")
		)
		(pad "10" smd rect
			(at 1.6256 2.80543 180)
			(size 0.3556 1.524)
			(layers "F.Cu" "F.Mask" "F.Paste")
			(net "SAS_HDD_PRE4")
		)
		(pad "11" smd rect
			(at 2.27457 2.80543 180)
			(size 0.3556 1.524)
			(layers "F.Cu" "F.Mask" "F.Paste")
			(net "SAS_HDD_PRE5")
		)
		(pad "12" smd rect
			(at 2.92481 2.80543 180)
			(size 0.3556 1.524)
			(layers "F.Cu" "F.Mask" "F.Paste")
			(net "SAS_HDD_PRE6")
		)
		(pad "13" smd rect
			(at 3.57505 2.80543 180)
			(size 0.3556 1.524)
			(layers "F.Cu" "F.Mask" "F.Paste")
			(net "SAS_HDD_PRE7")
		)
		(pad "14" smd rect
			(at 4.22529 2.80543 180)
			(size 0.3556 1.524)
			(layers "F.Cu" "F.Mask" "F.Paste")
			(net "HDD_PRE_IO_INT_N")
		)
		(pad "15" smd rect
			(at 4.22529 -2.80543 180)
			(size 0.3556 1.524)
			(layers "F.Cu" "F.Mask" "F.Paste")
			(net "IO_EXP_HDD_PRE_A2")
		)
		(pad "16" smd rect
			(at 3.57505 -2.80543 180)
			(size 0.3556 1.524)
			(layers "F.Cu" "F.Mask" "F.Paste")
			(net "GND")
		)
		(pad "17" smd rect
			(at 2.92481 -2.80543 180)
			(size 0.3556 1.524)
			(layers "F.Cu" "F.Mask" "F.Paste")
			(net "SAS_HDD_PRE15")
		)
		(pad "18" smd rect
			(at 2.27457 -2.80543 180)
			(size 0.3556 1.524)
			(layers "F.Cu" "F.Mask" "F.Paste")
			(net "SAS_HDD_PRE14")
		)
		(pad "19" smd rect
			(at 1.6256 -2.80543 180)
			(size 0.3556 1.524)
			(layers "F.Cu" "F.Mask" "F.Paste")
			(net "SAS_HDD_PRE13")
		)
		(pad "20" smd rect
			(at 0.97536 -2.80543 180)
			(size 0.3556 1.524)
			(layers "F.Cu" "F.Mask" "F.Paste")
			(net "SAS_HDD_PRE12")
		)
		(pad "21" smd rect
			(at 0.32512 -2.80543 180)
			(size 0.3556 1.524)
			(layers "F.Cu" "F.Mask" "F.Paste")
			(net "P3V3_STBY")
		)
		(pad "22" smd rect
			(at -0.32512 -2.80543 180)
			(size 0.3556 1.524)
			(layers "F.Cu" "F.Mask" "F.Paste")
			(net "IO_EXP_HDD_PRE_A3")
		)
		(pad "23" smd rect
			(at -0.97536 -2.80543 180)
			(size 0.3556 1.524)
			(layers "F.Cu" "F.Mask" "F.Paste")
			(net "SAS_HDD_PRE11")
		)
		(pad "24" smd rect
			(at -1.6256 -2.80543 180)
			(size 0.3556 1.524)
			(layers "F.Cu" "F.Mask" "F.Paste")
			(net "SAS_HDD_PRE10")
		)
		(pad "25" smd rect
			(at -2.27457 -2.80543 180)
			(size 0.3556 1.524)
			(layers "F.Cu" "F.Mask" "F.Paste")
			(net "SAS_HDD_PRE9")
		)
		(pad "26" smd rect
			(at -2.92481 -2.80543 180)
			(size 0.3556 1.524)
			(layers "F.Cu" "F.Mask" "F.Paste")
			(net "SAS_HDD_PRE8")
		)
		(pad "27" smd rect
			(at -3.57505 -2.80543 180)
			(size 0.3556 1.524)
			(layers "F.Cu" "F.Mask" "F.Paste")
			(net "PRE_SDA")
		)
		(pad "28" smd rect
			(at -4.22529 -2.80543 180)
			(size 0.3556 1.524)
			(layers "F.Cu" "F.Mask" "F.Paste")
			(net "PRE_SCL")
		)
	)
	(footprint ""
		(layer "F.Cu")
		(at 303.318672 -68.21424 -90)
		(property "Reference" "R271"
			(at 0 0 270)
			(layer "F.SilkS")
			(hide yes)
			(effects
				(font
					(size 1.27 1.27)
				)
			)
		)
		(property "Value" "0R2J-2-GP"
			(at 0.064008 -3.993896 270)
			(unlocked yes)
			(layer "F.Fab")
			(hide yes)
			(effects
				(font
					(size 1.016 1.016)
					(thickness 0.1524)
				)
			)
		)
		(property "Device Type" "R402H16"
			(at 0.064008 -5.517896 270)
			(unlocked yes)
			(layer "F.Fab")
			(hide yes)
			(effects
				(font
					(size 1.016 1.016)
					(thickness 0.1524)
				)
			)
		)
		(duplicate_pad_numbers_are_jumpers no)
		(fp_line
			(start -0.508 -0.9398)
			(end -0.508 0.9398)
			(stroke
				(width 0.1524)
				(type default)
			)
			(layer "F.SilkS")
		)
		(fp_line
			(start 0.508 -0.9398)
			(end -0.508 -0.9398)
			(stroke
				(width 0.1524)
				(type default)
			)
			(layer "F.SilkS")
		)
		(fp_rect
			(start -0.508 0.9398)
			(end 0.508 -0.9398)
			(stroke
				(width 0)
				(type default)
			)
			(fill no)
			(layer "F.CrtYd")
		)
		(fp_rect
			(start -0.508 0.9398)
			(end 0.508 -0.9398)
			(stroke
				(width 0)
				(type default)
			)
			(fill no)
			(layer "F.Fab")
		)
		(pad "1" smd custom
			(at 0 -0.4445 270)
			(size 0.1397 0.1397)
			(layers "F.Cu" "F.Mask" "F.Paste")
			(net "PCIE_10G_REFCLK_N")
			(options
				(clearance outline)
				(anchor circle)
			)
			(primitives
				(gr_poly
					(pts
						(arc
							(start -0.1778 -0.2794)
							(mid -0.249642 -0.249642)
							(end -0.2794 -0.1778)
						)
						(arc
							(start -0.2794 0.1778)
							(mid -0.249642 0.249642)
							(end -0.1778 0.2794)
						)
						(arc
							(start 0.1778 0.2794)
							(mid 0.249642 0.249642)
							(end 0.2794 0.1778)
						)
						(arc
							(start 0.2794 -0.1778)
							(mid 0.249642 -0.249642)
							(end 0.1778 -0.2794)
						)
					)
					(width 0)
					(fill yes)
				)
			)
		)
		(pad "2" smd custom
			(at 0 0.4445 270)
			(size 0.1397 0.1397)
			(layers "F.Cu" "F.Mask" "F.Paste")
			(net "CLK_100M_CLKBUFF_ENET1_DN")
			(options
				(clearance outline)
				(anchor circle)
			)
			(primitives
				(gr_poly
					(pts
						(arc
							(start -0.1778 -0.2794)
							(mid -0.249642 -0.249642)
							(end -0.2794 -0.1778)
						)
						(arc
							(start -0.2794 0.1778)
							(mid -0.249642 0.249642)
							(end -0.1778 0.2794)
						)
						(arc
							(start 0.1778 0.2794)
							(mid 0.249642 0.249642)
							(end 0.2794 0.1778)
						)
						(arc
							(start 0.2794 -0.1778)
							(mid 0.249642 -0.249642)
							(end 0.1778 -0.2794)
						)
					)
					(width 0)
					(fill yes)
				)
			)
		)
	)
)
